FILE_TYPE = CONNECTIVITY;
{Allegro Design Entry HDL 16.6-p007 (v16-6-112F) 10/10/2012}
"PAGE_NUMBER" = 57;
0"NC";
1"M_G_DQS_DP<17:0>";
2"M_G_DQS_DN<17:0>";
3"M_G_MA<17:0>";
4"M_G_BA<1:0>";
5"M_G_BG<1:0>";
6"M_G_CKE<3:0>";
7"M_G_CS_N<7:0>";
8"M_G_ODT<3:0>";
9"M_G_DQ<63:0>";
10"M_G_CLK_DN<3:0>";
11"M_G_CLK_DP<3:0>";
12"M_G_ECC<7:0>";
13"M_G_C<2>";
14"M_G_ECC<0>";
15"M_G_ECC<1>";
16"M_G_ECC<2>";
17"M_G_ECC<3>";
18"M_G_ECC<4>";
19"M_G_ECC<5>";
20"M_G_ECC<6>";
21"M_G_ECC<7>";
22"M_G_DQ<0>";
23"M_G_DQ<1>";
24"M_G_DQ<2>";
25"M_G_DQ<3>";
26"M_G_DQ<4>";
27"M_G_DQ<5>";
28"M_G_DQ<6>";
29"M_G_DQ<7>";
30"M_G_DQ<8>";
31"M_G_DQ<9>";
32"M_G_DQ<10>";
33"M_G_CLK_DP<0>";
34"M_G_CLK_DP<1>";
35"M_G_CLK_DP<2>";
36"M_G_CLK_DP<3>";
37"M_G_CLK_DN<0>";
38"M_G_CLK_DN<1>";
39"M_G_CLK_DN<2>";
40"M_G_CLK_DN<3>";
41"M_G_DQ<11>";
42"M_G_DQ<12>";
43"M_G_DQ<13>";
44"M_G_DQ<14>";
45"M_G_DQ<15>";
46"M_G_DQ<16>";
47"M_G_DQ<17>";
48"M_G_DQ<18>";
49"M_G_DQ<19>";
50"M_G_DQ<20>";
51"M_G_DQ<21>";
52"M_G_DQ<22>";
53"M_G_DQ<23>";
54"M_G_DQ<24>";
55"M_G_DQ<25>";
56"M_G_DQ<26>";
57"M_G_DQ<27>";
58"M_G_DQ<28>";
59"M_G_DQ<29>";
60"M_G_DQ<30>";
61"M_G_DQ<31>";
62"M_G_DQ<32>";
63"M_G_DQ<33>";
64"M_G_DQ<34>";
65"M_G_DQ<35>";
66"M_G_DQ<36>";
67"M_G_DQ<37>";
68"M_G_DQ<38>";
69"M_G_DQ<39>";
70"M_G_DQ<40>";
71"M_G_DQ<41>";
72"M_G_DQ<42>";
73"M_G_DQ<43>";
74"M_G_DQ<44>";
75"M_G_DQ<45>";
76"M_G_DQ<46>";
77"M_G_DQ<47>";
78"M_G_DQ<48>";
79"M_G_DQ<49>";
80"M_G_DQ<50>";
81"M_G_DQ<51>";
82"M_G_DQ<52>";
83"M_G_DQ<53>";
84"M_G_DQ<54>";
85"M_G_DQ<55>";
86"M_G_DQ<56>";
87"M_G_DQ<57>";
88"M_G_DQ<58>";
89"M_G_DQ<59>";
90"M_G_DQ<60>";
91"M_G_DQ<61>";
92"M_G_DQ<62>";
93"M_G_DQ<63>";
94"M_G_ODT<0>";
95"M_G_ODT<1>";
96"M_G_ODT<2>";
97"M_G_ODT<3>";
98"M_G_MA<0>";
99"M_G_MA<1>";
100"M_G_MA<2>";
101"M_G_CS_N<0>";
102"M_G_CS_N<1>";
103"M_G_CS_N<2>";
104"M_G_CS_N<3>";
105"M_G_CS_N<4>";
106"M_G_CS_N<5>";
107"M_G_CS_N<6>";
108"M_G_CS_N<7>";
109"M_G_CKE<0>";
110"M_G_CKE<1>";
111"M_G_CKE<2>";
112"M_G_CKE<3>";
113"M_G_BG<0>";
114"M_G_BG<1>";
115"M_G_BA<0>";
116"M_G_BA<1>";
117"M_G_PAR";
118"M_G_ALERT_N";
119"M_G_ACT_N";
120"M_G_MA<3>";
121"M_G_MA<4>";
122"M_G_MA<5>";
123"M_G_MA<6>";
124"M_G_MA<7>";
125"M_G_MA<8>";
126"M_G_MA<9>";
127"M_G_MA<10>";
128"M_G_MA<11>";
129"M_G_MA<12>";
130"M_G_MA<13>";
131"M_G_MA<14>";
132"M_G_MA<15>";
133"M_G_MA<16>";
134"M_G_MA<17>";
135"M_G_DQS_DP<0>";
136"M_G_DQS_DP<1>";
137"M_G_DQS_DP<2>";
138"M_G_DQS_DP<3>";
139"M_G_DQS_DP<4>";
140"M_G_DQS_DP<5>";
141"M_G_DQS_DN<0>";
142"M_G_DQS_DN<1>";
143"M_G_DQS_DN<2>";
144"M_G_DQS_DN<3>";
145"M_G_DQS_DN<4>";
146"M_G_DQS_DN<5>";
147"M_G_DQS_DN<6>";
148"M_G_DQS_DN<7>";
149"M_G_DQS_DN<8>";
150"M_G_DQS_DN<9>";
151"M_G_DQS_DN<10>";
152"M_G_DQS_DN<11>";
153"M_G_DQS_DN<12>";
154"M_G_DQS_DN<13>";
155"M_G_DQS_DN<14>";
156"M_G_DQS_DN<15>";
157"M_G_DQS_DN<16>";
158"M_G_DQS_DN<17>";
159"M_G_DQS_DP<6>";
160"M_G_DQS_DP<7>";
161"M_G_DQS_DP<8>";
162"M_G_DQS_DP<9>";
163"M_G_DQS_DP<10>";
164"M_G_DQS_DP<11>";
165"M_G_DQS_DP<12>";
166"M_G_DQS_DP<13>";
167"M_G_DQS_DP<14>";
168"M_G_DQS_DP<15>";
169"M_G_DQS_DP<16>";
170"M_G_DQS_DP<17>";
%"TAP"
"6","(-5575,825)","0","mstr_standard","I10";
;
HDL_TAP"TRUE"
BODY_TYPE"PLUMBING"
CDS_LIB"mstr_standard";
"B \NAC \NWC"11;
"S \NAC"
BN"0"33;
%"TAP"
"6","(-2850,1575)","2","mstr_standard","I100";
;
HDL_TAP"TRUE"
BODY_TYPE"PLUMBING"
CDS_LIB"mstr_standard";
"B \NAC \NWC"8;
"S \NAC"
BN"3"97;
%"TAP"
"6","(-2850,1525)","2","mstr_standard","I101";
;
HDL_TAP"TRUE"
BODY_TYPE"PLUMBING"
CDS_LIB"mstr_standard";
"B \NAC \NWC"8;
"S \NAC"
BN"2"96;
%"TAP"
"6","(-2850,1475)","2","mstr_standard","I102";
;
HDL_TAP"TRUE"
BODY_TYPE"PLUMBING"
CDS_LIB"mstr_standard";
"B \NAC \NWC"8;
"S \NAC"
BN"1"95;
%"TAP"
"6","(-2850,1675)","2","mstr_standard","I103";
;
HDL_TAP"TRUE"
BODY_TYPE"PLUMBING"
CDS_LIB"mstr_standard";
"B \NAC \NWC"6;
"S \NAC"
BN"0"109;
%"TAP"
"6","(-2850,1725)","2","mstr_standard","I104";
;
HDL_TAP"TRUE"
BODY_TYPE"PLUMBING"
CDS_LIB"mstr_standard";
"B \NAC \NWC"6;
"S \NAC"
BN"1"110;
%"TAP"
"6","(-2850,1775)","2","mstr_standard","I105";
;
HDL_TAP"TRUE"
BODY_TYPE"PLUMBING"
CDS_LIB"mstr_standard";
"B \NAC \NWC"6;
"S \NAC"
BN"2"111;
%"TAP"
"6","(-2850,1825)","2","mstr_standard","I106";
;
HDL_TAP"TRUE"
BODY_TYPE"PLUMBING"
CDS_LIB"mstr_standard";
"B \NAC \NWC"6;
"S \NAC"
BN"3"112;
%"TAP"
"6","(-2850,1925)","2","mstr_standard","I107";
;
HDL_TAP"TRUE"
BODY_TYPE"PLUMBING"
CDS_LIB"mstr_standard";
"B \NAC \NWC"3;
"S \NAC"
BN"0"98;
%"TAP"
"6","(-2850,1975)","2","mstr_standard","I108";
;
HDL_TAP"TRUE"
BODY_TYPE"PLUMBING"
CDS_LIB"mstr_standard";
"B \NAC \NWC"3;
"S \NAC"
BN"1"99;
%"TAP"
"6","(-2850,2075)","2","mstr_standard","I109";
;
HDL_TAP"TRUE"
BODY_TYPE"PLUMBING"
CDS_LIB"mstr_standard";
"B \NAC \NWC"3;
"S \NAC"
BN"3"120;
%"TAP"
"6","(-5575,925)","0","mstr_standard","I11";
;
HDL_TAP"TRUE"
BODY_TYPE"PLUMBING"
CDS_LIB"mstr_standard";
"B \NAC \NWC"11;
"S \NAC"
BN"2"35;
%"TAP"
"6","(-2850,2025)","2","mstr_standard","I110";
;
HDL_TAP"TRUE"
BODY_TYPE"PLUMBING"
CDS_LIB"mstr_standard";
"B \NAC \NWC"3;
"S \NAC"
BN"2"100;
%"TAP"
"6","(-2850,2125)","2","mstr_standard","I111";
;
HDL_TAP"TRUE"
BODY_TYPE"PLUMBING"
CDS_LIB"mstr_standard";
"B \NAC \NWC"3;
"S \NAC"
BN"4"121;
%"TAP"
"6","(-2850,2175)","2","mstr_standard","I112";
;
HDL_TAP"TRUE"
BODY_TYPE"PLUMBING"
CDS_LIB"mstr_standard";
"B \NAC \NWC"3;
"S \NAC"
BN"5"122;
%"TAP"
"6","(-2850,2225)","2","mstr_standard","I113";
;
HDL_TAP"TRUE"
BODY_TYPE"PLUMBING"
CDS_LIB"mstr_standard";
"B \NAC \NWC"3;
"S \NAC"
BN"6"123;
%"TAP"
"6","(-2850,2325)","2","mstr_standard","I114";
;
HDL_TAP"TRUE"
BODY_TYPE"PLUMBING"
CDS_LIB"mstr_standard";
"B \NAC \NWC"3;
"S \NAC"
BN"8"125;
%"TAP"
"6","(-2850,2275)","2","mstr_standard","I115";
;
HDL_TAP"TRUE"
BODY_TYPE"PLUMBING"
CDS_LIB"mstr_standard";
"B \NAC \NWC"3;
"S \NAC"
BN"7"124;
%"TAP"
"6","(-2850,2475)","2","mstr_standard","I116";
;
HDL_TAP"TRUE"
BODY_TYPE"PLUMBING"
CDS_LIB"mstr_standard";
"B \NAC \NWC"3;
"S \NAC"
BN"11"128;
%"TAP"
"6","(-2850,2425)","2","mstr_standard","I117";
;
HDL_TAP"TRUE"
BODY_TYPE"PLUMBING"
CDS_LIB"mstr_standard";
"B \NAC \NWC"3;
"S \NAC"
BN"10"127;
%"TAP"
"6","(-2850,2375)","2","mstr_standard","I118";
;
HDL_TAP"TRUE"
BODY_TYPE"PLUMBING"
CDS_LIB"mstr_standard";
"B \NAC \NWC"3;
"S \NAC"
BN"9"126;
%"TAP"
"6","(-2850,2525)","2","mstr_standard","I119";
;
HDL_TAP"TRUE"
BODY_TYPE"PLUMBING"
CDS_LIB"mstr_standard";
"B \NAC \NWC"3;
"S \NAC"
BN"12"129;
%"TAP"
"6","(-5575,975)","0","mstr_standard","I12";
;
HDL_TAP"TRUE"
BODY_TYPE"PLUMBING"
CDS_LIB"mstr_standard";
"B \NAC \NWC"11;
"S \NAC"
BN"3"36;
%"TAP"
"6","(-2850,2575)","2","mstr_standard","I120";
;
HDL_TAP"TRUE"
BODY_TYPE"PLUMBING"
CDS_LIB"mstr_standard";
"B \NAC \NWC"3;
"S \NAC"
BN"13"130;
%"TAP"
"6","(-2850,2625)","2","mstr_standard","I121";
;
HDL_TAP"TRUE"
BODY_TYPE"PLUMBING"
CDS_LIB"mstr_standard";
"B \NAC \NWC"3;
"S \NAC"
BN"14"131;
%"TAP"
"6","(-2850,2675)","2","mstr_standard","I122";
;
HDL_TAP"TRUE"
BODY_TYPE"PLUMBING"
CDS_LIB"mstr_standard";
"B \NAC \NWC"3;
"S \NAC"
BN"15"132;
%"TAP"
"6","(-2850,2725)","2","mstr_standard","I123";
;
HDL_TAP"TRUE"
BODY_TYPE"PLUMBING"
CDS_LIB"mstr_standard";
"B \NAC \NWC"3;
"S \NAC"
BN"16"133;
%"TAP"
"6","(-2850,2775)","2","mstr_standard","I124";
;
HDL_TAP"TRUE"
BODY_TYPE"PLUMBING"
CDS_LIB"mstr_standard";
"B \NAC \NWC"3;
"S \NAC"
BN"17"134;
%"TAP"
"6","(-2850,2925)","2","mstr_standard","I125";
;
HDL_TAP"TRUE"
BODY_TYPE"PLUMBING"
CDS_LIB"mstr_standard";
"B \NAC \NWC"2;
"S \NAC"
BN"1"142;
%"TAP"
"6","(-2850,2975)","2","mstr_standard","I126";
;
HDL_TAP"TRUE"
BODY_TYPE"PLUMBING"
CDS_LIB"mstr_standard";
"B \NAC \NWC"2;
"S \NAC"
BN"2"143;
%"TAP"
"6","(-2850,2875)","2","mstr_standard","I127";
;
HDL_TAP"TRUE"
BODY_TYPE"PLUMBING"
CDS_LIB"mstr_standard";
"B \NAC \NWC"2;
"S \NAC"
BN"0"141;
%"TAP"
"6","(-2850,3075)","2","mstr_standard","I128";
;
HDL_TAP"TRUE"
BODY_TYPE"PLUMBING"
CDS_LIB"mstr_standard";
"B \NAC \NWC"2;
"S \NAC"
BN"4"145;
%"TAP"
"6","(-2850,3025)","2","mstr_standard","I129";
;
HDL_TAP"TRUE"
BODY_TYPE"PLUMBING"
CDS_LIB"mstr_standard";
"B \NAC \NWC"2;
"S \NAC"
BN"3"144;
%"TAP"
"6","(-5575,1075)","0","mstr_standard","I13";
;
HDL_TAP"TRUE"
BODY_TYPE"PLUMBING"
CDS_LIB"mstr_standard";
"B \NAC \NWC"12;
"S \NAC"
BN"0"14;
%"TAP"
"6","(-2850,3125)","2","mstr_standard","I130";
;
HDL_TAP"TRUE"
BODY_TYPE"PLUMBING"
CDS_LIB"mstr_standard";
"B \NAC \NWC"2;
"S \NAC"
BN"5"146;
%"TAP"
"6","(-2850,3175)","2","mstr_standard","I131";
;
HDL_TAP"TRUE"
BODY_TYPE"PLUMBING"
CDS_LIB"mstr_standard";
"B \NAC \NWC"2;
"S \NAC"
BN"6"147;
%"TAP"
"6","(-2850,3225)","2","mstr_standard","I132";
;
HDL_TAP"TRUE"
BODY_TYPE"PLUMBING"
CDS_LIB"mstr_standard";
"B \NAC \NWC"2;
"S \NAC"
BN"7"148;
%"TAP"
"6","(-2850,3275)","2","mstr_standard","I133";
;
HDL_TAP"TRUE"
BODY_TYPE"PLUMBING"
CDS_LIB"mstr_standard";
"B \NAC \NWC"2;
"S \NAC"
BN"8"149;
%"TAP"
"6","(-2850,3325)","2","mstr_standard","I134";
;
HDL_TAP"TRUE"
BODY_TYPE"PLUMBING"
CDS_LIB"mstr_standard";
"B \NAC \NWC"2;
"S \NAC"
BN"9"150;
%"TAP"
"6","(-2850,3375)","2","mstr_standard","I135";
;
HDL_TAP"TRUE"
BODY_TYPE"PLUMBING"
CDS_LIB"mstr_standard";
"B \NAC \NWC"2;
"S \NAC"
BN"10"151;
%"TAP"
"6","(-2850,3475)","2","mstr_standard","I136";
;
HDL_TAP"TRUE"
BODY_TYPE"PLUMBING"
CDS_LIB"mstr_standard";
"B \NAC \NWC"2;
"S \NAC"
BN"12"153;
%"TAP"
"6","(-2850,3425)","2","mstr_standard","I137";
;
HDL_TAP"TRUE"
BODY_TYPE"PLUMBING"
CDS_LIB"mstr_standard";
"B \NAC \NWC"2;
"S \NAC"
BN"11"152;
%"TAP"
"6","(-2850,3625)","2","mstr_standard","I138";
;
HDL_TAP"TRUE"
BODY_TYPE"PLUMBING"
CDS_LIB"mstr_standard";
"B \NAC \NWC"2;
"S \NAC"
BN"15"156;
%"TAP"
"6","(-2850,3575)","2","mstr_standard","I139";
;
HDL_TAP"TRUE"
BODY_TYPE"PLUMBING"
CDS_LIB"mstr_standard";
"B \NAC \NWC"2;
"S \NAC"
BN"14"155;
%"TAP"
"6","(-5575,1125)","0","mstr_standard","I14";
;
HDL_TAP"TRUE"
BODY_TYPE"PLUMBING"
CDS_LIB"mstr_standard";
"B \NAC \NWC"12;
"S \NAC"
BN"1"15;
%"TAP"
"6","(-2850,3525)","2","mstr_standard","I140";
;
HDL_TAP"TRUE"
BODY_TYPE"PLUMBING"
CDS_LIB"mstr_standard";
"B \NAC \NWC"2;
"S \NAC"
BN"13"154;
%"TAP"
"6","(-2850,3675)","2","mstr_standard","I141";
;
HDL_TAP"TRUE"
BODY_TYPE"PLUMBING"
CDS_LIB"mstr_standard";
"B \NAC \NWC"2;
"S \NAC"
BN"16"157;
%"TAP"
"6","(-2850,3725)","2","mstr_standard","I142";
;
HDL_TAP"TRUE"
BODY_TYPE"PLUMBING"
CDS_LIB"mstr_standard";
"B \NAC \NWC"2;
"S \NAC"
BN"17"158;
%"TAP"
"6","(-2850,3825)","2","mstr_standard","I143";
;
HDL_TAP"TRUE"
BODY_TYPE"PLUMBING"
CDS_LIB"mstr_standard";
"B \NAC \NWC"1;
"S \NAC"
BN"0"135;
%"TAP"
"6","(-2850,3875)","2","mstr_standard","I144";
;
HDL_TAP"TRUE"
BODY_TYPE"PLUMBING"
CDS_LIB"mstr_standard";
"B \NAC \NWC"1;
"S \NAC"
BN"1"136;
%"TAP"
"6","(-2850,3925)","2","mstr_standard","I145";
;
HDL_TAP"TRUE"
BODY_TYPE"PLUMBING"
CDS_LIB"mstr_standard";
"B \NAC \NWC"1;
"S \NAC"
BN"2"137;
%"TAP"
"6","(-2850,3975)","2","mstr_standard","I146";
;
HDL_TAP"TRUE"
BODY_TYPE"PLUMBING"
CDS_LIB"mstr_standard";
"B \NAC \NWC"1;
"S \NAC"
BN"3"138;
%"TAP"
"6","(-5575,1175)","0","mstr_standard","I15";
;
HDL_TAP"TRUE"
BODY_TYPE"PLUMBING"
CDS_LIB"mstr_standard";
"B \NAC \NWC"12;
"S \NAC"
BN"2"16;
%"TAP"
"6","(-2850,4025)","2","mstr_standard","I157";
;
HDL_TAP"TRUE"
BODY_TYPE"PLUMBING"
CDS_LIB"mstr_standard";
"B \NAC \NWC"1;
"S \NAC"
BN"4"139;
%"TAP"
"6","(-2850,4125)","2","mstr_standard","I158";
;
HDL_TAP"TRUE"
BODY_TYPE"PLUMBING"
CDS_LIB"mstr_standard";
"B \NAC \NWC"1;
"S \NAC"
BN"6"159;
%"TAP"
"6","(-2850,4075)","2","mstr_standard","I159";
;
HDL_TAP"TRUE"
BODY_TYPE"PLUMBING"
CDS_LIB"mstr_standard";
"B \NAC \NWC"1;
"S \NAC"
BN"5"140;
%"TAP"
"6","(-5575,1275)","0","mstr_standard","I16";
;
HDL_TAP"TRUE"
BODY_TYPE"PLUMBING"
CDS_LIB"mstr_standard";
"B \NAC \NWC"12;
"S \NAC"
BN"4"18;
%"TAP"
"6","(-2850,4175)","2","mstr_standard","I160";
;
HDL_TAP"TRUE"
BODY_TYPE"PLUMBING"
CDS_LIB"mstr_standard";
"B \NAC \NWC"1;
"S \NAC"
BN"7"160;
%"TAP"
"6","(-2850,4225)","2","mstr_standard","I161";
;
HDL_TAP"TRUE"
BODY_TYPE"PLUMBING"
CDS_LIB"mstr_standard";
"B \NAC \NWC"1;
"S \NAC"
BN"8"161;
%"TAP"
"6","(-2850,4275)","2","mstr_standard","I162";
;
HDL_TAP"TRUE"
BODY_TYPE"PLUMBING"
CDS_LIB"mstr_standard";
"B \NAC \NWC"1;
"S \NAC"
BN"9"162;
%"TAP"
"6","(-2850,4325)","2","mstr_standard","I163";
;
HDL_TAP"TRUE"
BODY_TYPE"PLUMBING"
CDS_LIB"mstr_standard";
"B \NAC \NWC"1;
"S \NAC"
BN"10"163;
%"TAP"
"6","(-2850,4375)","2","mstr_standard","I164";
;
HDL_TAP"TRUE"
BODY_TYPE"PLUMBING"
CDS_LIB"mstr_standard";
"B \NAC \NWC"1;
"S \NAC"
BN"11"164;
%"TAP"
"6","(-2850,4525)","2","mstr_standard","I165";
;
HDL_TAP"TRUE"
BODY_TYPE"PLUMBING"
CDS_LIB"mstr_standard";
"B \NAC \NWC"1;
"S \NAC"
BN"14"167;
%"TAP"
"6","(-2850,4475)","2","mstr_standard","I166";
;
HDL_TAP"TRUE"
BODY_TYPE"PLUMBING"
CDS_LIB"mstr_standard";
"B \NAC \NWC"1;
"S \NAC"
BN"13"166;
%"TAP"
"6","(-2850,4425)","2","mstr_standard","I167";
;
HDL_TAP"TRUE"
BODY_TYPE"PLUMBING"
CDS_LIB"mstr_standard";
"B \NAC \NWC"1;
"S \NAC"
BN"12"165;
%"TAP"
"6","(-2850,4575)","2","mstr_standard","I168";
;
HDL_TAP"TRUE"
BODY_TYPE"PLUMBING"
CDS_LIB"mstr_standard";
"B \NAC \NWC"1;
"S \NAC"
BN"15"168;
%"TAP"
"6","(-2850,4625)","2","mstr_standard","I169";
;
HDL_TAP"TRUE"
BODY_TYPE"PLUMBING"
CDS_LIB"mstr_standard";
"B \NAC \NWC"1;
"S \NAC"
BN"16"169;
%"TAP"
"6","(-5575,1225)","0","mstr_standard","I17";
;
HDL_TAP"TRUE"
BODY_TYPE"PLUMBING"
CDS_LIB"mstr_standard";
"B \NAC \NWC"12;
"S \NAC"
BN"3"17;
%"TAP"
"6","(-2850,4675)","2","mstr_standard","I170";
;
HDL_TAP"TRUE"
BODY_TYPE"PLUMBING"
CDS_LIB"mstr_standard";
"B \NAC \NWC"1;
"S \NAC"
BN"17"170;
%"SKX_EXT_B"
"3","(-4175,2575)","0","chpset_lib","I172";
;
CDS_SEC"3"
CDS_LOCATION"U2D1"
SEC"3"
CDS_LIB"chpset_lib"
SEC_TYPE"BGA1"
PACK_TYPE"BGA1"
MATERIAL"IC"
PART_NUMBER"TBD"
LOCATION"U2D1";
"DDR0_PAR"
$PN"D53"117;
"DDR0_ODT<0>"
$PN"C50"94;
"DDR0_ODT<1>"
$PN"C48"95;
"DDR0_ODT<2>"
$PN"G50"96;
"DDR0_ODT<3>"
$PN"G48"97;
"DDR0_MA<0>"
$PN"F53"98;
"DDR0_MA<1>"
$PN"F57"99;
"DDR0_MA<2>"
$PN"D57"100;
"DDR0_MA<3>"
$PN"C58"120;
"DDR0_MA<4>"
$PN"G58"121;
"DDR0_MA<5>"
$PN"F59"122;
"DDR0_MA<6>"
$PN"D59"123;
"DDR0_MA<7>"
$PN"G60"124;
"DDR0_MA<8>"
$PN"C60"125;
"DDR0_MA<9>"
$PN"F61"126;
"DDR0_MA<10>"
$PN"J54"127;
"DDR0_MA<11>"
$PN"G62"128;
"DDR0_MA<12>"
$PN"J64"129;
"DDR0_MA<13>"
$PN"J48"130;
"DDR0_MA<14>"
$PN"F51"131;
"DDR0_MA<15>"
$PN"K49"132;
"DDR0_MA<16>"
$PN"D51"133;
"DDR0_MA<17>"
$PN"K47"134;
"DDR0_ECC<0>"
$PN"AC68"14;
"DDR0_ECC<1>"
$PN"AG68"15;
"DDR0_ECC<2>"
$PN"AD65"16;
"DDR0_ECC<3>"
$PN"AF65"17;
"DDR0_ECC<4>"
$PN"AD69"18;
"DDR0_ECC<5>"
$PN"AF69"19;
"DDR0_ECC<6>"
$PN"AC66"20;
"DDR0_ECC<7>"
$PN"AG66"21;
"DDR0_DQS_DP<0>"
$PN"AH85"135;
"DDR0_DQS_DP<1>"
$PN"P85"136;
"DDR0_DQS_DP<2>"
$PN"R80"137;
"DDR0_DQS_DP<3>"
$PN"P75"138;
"DDR0_DQS_DP<4>"
$PN"E40"139;
"DDR0_DQS_DP<5>"
$PN"N36"140;
"DDR0_DQS_DP<6>"
$PN"N30"159;
"DDR0_DQS_DP<7>"
$PN"R24"160;
"DDR0_DQS_DP<8>"
$PN"AF67"161;
"DDR0_DQS_DP<9>"
$PN"AM85"162;
"DDR0_DQS_DP<10>"
$PN"V85"163;
"DDR0_DQS_DP<11>"
$PN"T81"164;
"DDR0_DQS_DP<12>"
$PN"M75"165;
"DDR0_DQS_DP<13>"
$PN"C40"166;
"DDR0_DQS_DP<14>"
$PN"L36"167;
"DDR0_DQS_DP<15>"
$PN"L30"168;
"DDR0_DQS_DP<16>"
$PN"L24"169;
"DDR0_DQS_DP<17>"
$PN"AD67"170;
"DDR0_DQS_DN<0>"
$PN"AJ84"141;
"DDR0_DQS_DN<1>"
$PN"R84"142;
"DDR0_DQS_DN<2>"
$PN"P79"143;
"DDR0_DQS_DN<3>"
$PN"T75"144;
"DDR0_DQS_DN<4>"
$PN"G40"145;
"DDR0_DQS_DN<5>"
$PN"R36"146;
"DDR0_DQS_DN<6>"
$PN"R30"147;
"DDR0_DQS_DN<7>"
$PN"N24"148;
"DDR0_DQS_DN<8>"
$PN"AH67"149;
"DDR0_DQS_DN<9>"
$PN"AL84"150;
"DDR0_DQS_DN<10>"
$PN"U84"151;
"DDR0_DQS_DN<11>"
$PN"U82"152;
"DDR0_DQS_DN<12>"
$PN"K75"153;
"DDR0_DQS_DN<13>"
$PN"A40"154;
"DDR0_DQS_DN<14>"
$PN"J36"155;
"DDR0_DQS_DN<15>"
$PN"J30"156;
"DDR0_DQS_DN<16>"
$PN"J24"157;
"DDR0_DQS_DN<17>"
$PN"AB67"158;
"DDR0_DQ<0>"
$PN"AN86"22;
"DDR0_DQ<1>"
$PN"AN84"23;
"DDR0_DQ<2>"
$PN"AE86"24;
"DDR0_DQ<3>"
$PN"AE84"25;
"DDR0_DQ<4>"
$PN"AR86"26;
"DDR0_DQ<5>"
$PN"AR84"27;
"DDR0_DQ<6>"
$PN"AG86"28;
"DDR0_DQ<7>"
$PN"AG84"29;
"DDR0_DQ<8>"
$PN"W86"30;
"DDR0_DQ<9>"
$PN"W84"31;
"DDR0_DQ<10>"
$PN"L86"32;
"DDR0_DQ<11>"
$PN"L84"41;
"DDR0_DQ<12>"
$PN"AA86"42;
"DDR0_DQ<13>"
$PN"AA84"43;
"DDR0_DQ<14>"
$PN"N86"44;
"DDR0_DQ<15>"
$PN"N84"45;
"DDR0_DQ<16>"
$PN"V81"46;
"DDR0_DQ<17>"
$PN"T79"47;
"DDR0_DQ<18>"
$PN"N82"48;
"DDR0_DQ<19>"
$PN"M81"49;
"DDR0_DQ<20>"
$PN"W80"50;
"DDR0_DQ<21>"
$PN"V79"51;
"DDR0_DQ<22>"
$PN"R82"52;
"DDR0_DQ<23>"
$PN"N80"53;
"DDR0_DQ<24>"
$PN"L76"54;
"DDR0_DQ<25>"
$PN"R76"55;
"DDR0_DQ<26>"
$PN"M73"56;
"DDR0_DQ<27>"
$PN"P73"57;
"DDR0_DQ<28>"
$PN"M77"58;
"DDR0_DQ<29>"
$PN"P77"59;
"DDR0_DQ<30>"
$PN"L74"60;
"DDR0_DQ<31>"
$PN"R74"61;
"DDR0_DQ<32>"
$PN"C42"62;
"DDR0_DQ<33>"
$PN"B41"63;
"DDR0_DQ<34>"
$PN"C38"64;
"DDR0_DQ<35>"
$PN"E38"65;
"DDR0_DQ<36>"
$PN"E42"66;
"DDR0_DQ<37>"
$PN"F41"67;
"DDR0_DQ<38>"
$PN"B39"68;
"DDR0_DQ<39>"
$PN"F39"69;
"DDR0_DQ<40>"
$PN"K37"70;
"DDR0_DQ<41>"
$PN"P37"71;
"DDR0_DQ<42>"
$PN"L34"72;
"DDR0_DQ<43>"
$PN"N34"73;
"DDR0_DQ<44>"
$PN"L38"74;
"DDR0_DQ<45>"
$PN"N38"75;
"DDR0_DQ<46>"
$PN"K35"76;
"DDR0_DQ<47>"
$PN"P35"77;
"DDR0_DQ<48>"
$PN"K31"78;
"DDR0_DQ<49>"
$PN"P31"79;
"DDR0_DQ<50>"
$PN"L28"80;
"DDR0_DQ<51>"
$PN"N28"81;
"DDR0_DQ<52>"
$PN"L32"82;
"DDR0_DQ<53>"
$PN"N32"83;
"DDR0_DQ<54>"
$PN"K29"84;
"DDR0_DQ<55>"
$PN"P29"85;
"DDR0_DQ<56>"
$PN"K25"86;
"DDR0_DQ<57>"
$PN"P25"87;
"DDR0_DQ<58>"
$PN"P23"88;
"DDR0_DQ<59>"
$PN"T23"89;
"DDR0_DQ<60>"
$PN"L26"90;
"DDR0_DQ<61>"
$PN"N26"91;
"DDR0_DQ<62>"
$PN"H23"92;
"DDR0_DQ<63>"
$PN"K23"93;
"DDR0_CS_N<0>"
$PN"G52"101;
"DDR0_CS_N<1>"
$PN"F49"102;
"DDR0_CS_N<2>"
$PN"D47"103;
"DDR0_CS_N<3>"
$PN"F47"104;
"DDR0_CS_N<4>"
$PN"B51"105;
"DDR0_CS_N<5>"
$PN"D49"106;
"DDR0_CS_N<6>"
$PN"F45"107;
"DDR0_CS_N<7>"
$PN"K45"108;
"DDR0_CLK_DP<0>"
$PN"D55"33;
"DDR0_CLK_DP<1>"
$PN"B55"34;
"DDR0_CLK_DP<2>"
$PN"G56"35;
"DDR0_CLK_DP<3>"
$PN"B57"36;
"DDR0_CLK_DN<0>"
$PN"F55"37;
"DDR0_CLK_DN<1>"
$PN"C54"38;
"DDR0_CLK_DN<2>"
$PN"J56"39;
"DDR0_CLK_DN<3>"
$PN"C56"40;
"DDR0_CKE<0>"
$PN"C62"109;
"DDR0_CKE<1>"
$PN"C64"110;
"DDR0_CKE<2>"
$PN"B63"111;
"DDR0_CKE<3>"
$PN"D63"112;
"DDR0_CID<2>"
$PN"G46"13;
"DDR0_BG<0>"
$PN"D61"113;
"DDR0_BG<1>"
$PN"F63"114;
"DDR0_BA<0>"
$PN"C52"115;
"DDR0_BA<1>"
$PN"G54"116;
"DDR0_ALERT_N"
$PN"B61"118;
"DDR0_ACT_N"
$PN"J60"119;
%"TAP"
"6","(-5575,1325)","0","mstr_standard","I18";
;
HDL_TAP"TRUE"
BODY_TYPE"PLUMBING"
CDS_LIB"mstr_standard";
"B \NAC \NWC"12;
"S \NAC"
BN"5"19;
%"TAP"
"6","(-5575,1375)","0","mstr_standard","I19";
;
HDL_TAP"TRUE"
BODY_TYPE"PLUMBING"
CDS_LIB"mstr_standard";
"B \NAC \NWC"12;
"S \NAC"
BN"6"20;
%"TAP"
"6","(-5575,1425)","0","mstr_standard","I20";
;
HDL_TAP"TRUE"
BODY_TYPE"PLUMBING"
CDS_LIB"mstr_standard";
"B \NAC \NWC"12;
"S \NAC"
BN"7"21;
%"TAP"
"6","(-5575,1525)","0","mstr_standard","I21";
;
HDL_TAP"TRUE"
BODY_TYPE"PLUMBING"
CDS_LIB"mstr_standard";
"B \NAC \NWC"9;
"S \NAC"
BN"0"22;
%"TAP"
"6","(-5575,1575)","0","mstr_standard","I22";
;
HDL_TAP"TRUE"
BODY_TYPE"PLUMBING"
CDS_LIB"mstr_standard";
"B \NAC \NWC"9;
"S \NAC"
BN"1"23;
%"TAP"
"6","(-5575,1625)","0","mstr_standard","I23";
;
HDL_TAP"TRUE"
BODY_TYPE"PLUMBING"
CDS_LIB"mstr_standard";
"B \NAC \NWC"9;
"S \NAC"
BN"2"24;
%"TAP"
"6","(-5575,1675)","0","mstr_standard","I24";
;
HDL_TAP"TRUE"
BODY_TYPE"PLUMBING"
CDS_LIB"mstr_standard";
"B \NAC \NWC"9;
"S \NAC"
BN"3"25;
%"TAP"
"6","(-5575,1725)","0","mstr_standard","I25";
;
HDL_TAP"TRUE"
BODY_TYPE"PLUMBING"
CDS_LIB"mstr_standard";
"B \NAC \NWC"9;
"S \NAC"
BN"4"26;
%"TAP"
"6","(-5575,1775)","0","mstr_standard","I26";
;
HDL_TAP"TRUE"
BODY_TYPE"PLUMBING"
CDS_LIB"mstr_standard";
"B \NAC \NWC"9;
"S \NAC"
BN"5"27;
%"TAP"
"6","(-5575,1825)","0","mstr_standard","I27";
;
HDL_TAP"TRUE"
BODY_TYPE"PLUMBING"
CDS_LIB"mstr_standard";
"B \NAC \NWC"9;
"S \NAC"
BN"6"28;
%"TAP"
"6","(-5575,1925)","0","mstr_standard","I28";
;
HDL_TAP"TRUE"
BODY_TYPE"PLUMBING"
CDS_LIB"mstr_standard";
"B \NAC \NWC"9;
"S \NAC"
BN"8"30;
%"TAP"
"6","(-5575,1875)","0","mstr_standard","I29";
;
HDL_TAP"TRUE"
BODY_TYPE"PLUMBING"
CDS_LIB"mstr_standard";
"B \NAC \NWC"9;
"S \NAC"
BN"7"29;
%"TAP"
"6","(-5575,1975)","0","mstr_standard","I31";
;
HDL_TAP"TRUE"
BODY_TYPE"PLUMBING"
CDS_LIB"mstr_standard";
"B \NAC \NWC"9;
"S \NAC"
BN"9"31;
%"TAP"
"6","(-5575,2025)","0","mstr_standard","I32";
;
HDL_TAP"TRUE"
BODY_TYPE"PLUMBING"
CDS_LIB"mstr_standard";
"B \NAC \NWC"9;
"S \NAC"
BN"10"32;
%"TAP"
"6","(-5575,2075)","0","mstr_standard","I33";
;
HDL_TAP"TRUE"
BODY_TYPE"PLUMBING"
CDS_LIB"mstr_standard";
"B \NAC \NWC"9;
"S \NAC"
BN"11"41;
%"TAP"
"6","(-5575,2125)","0","mstr_standard","I34";
;
HDL_TAP"TRUE"
BODY_TYPE"PLUMBING"
CDS_LIB"mstr_standard";
"B \NAC \NWC"9;
"S \NAC"
BN"12"42;
%"TAP"
"6","(-5575,2175)","0","mstr_standard","I35";
;
HDL_TAP"TRUE"
BODY_TYPE"PLUMBING"
CDS_LIB"mstr_standard";
"B \NAC \NWC"9;
"S \NAC"
BN"13"43;
%"TAP"
"6","(-5575,2225)","0","mstr_standard","I36";
;
HDL_TAP"TRUE"
BODY_TYPE"PLUMBING"
CDS_LIB"mstr_standard";
"B \NAC \NWC"9;
"S \NAC"
BN"14"44;
%"TAP"
"6","(-5575,2275)","0","mstr_standard","I37";
;
HDL_TAP"TRUE"
BODY_TYPE"PLUMBING"
CDS_LIB"mstr_standard";
"B \NAC \NWC"9;
"S \NAC"
BN"15"45;
%"TAP"
"6","(-5575,2325)","0","mstr_standard","I38";
;
HDL_TAP"TRUE"
BODY_TYPE"PLUMBING"
CDS_LIB"mstr_standard";
"B \NAC \NWC"9;
"S \NAC"
BN"16"46;
%"TAP"
"6","(-5575,2375)","0","mstr_standard","I39";
;
HDL_TAP"TRUE"
BODY_TYPE"PLUMBING"
CDS_LIB"mstr_standard";
"B \NAC \NWC"9;
"S \NAC"
BN"17"47;
%"TAP"
"6","(-5575,2425)","0","mstr_standard","I40";
;
HDL_TAP"TRUE"
BODY_TYPE"PLUMBING"
CDS_LIB"mstr_standard";
"B \NAC \NWC"9;
"S \NAC"
BN"18"48;
%"TAP"
"6","(-5575,2475)","0","mstr_standard","I41";
;
HDL_TAP"TRUE"
BODY_TYPE"PLUMBING"
CDS_LIB"mstr_standard";
"B \NAC \NWC"9;
"S \NAC"
BN"19"49;
%"TAP"
"6","(-5575,2525)","0","mstr_standard","I42";
;
HDL_TAP"TRUE"
BODY_TYPE"PLUMBING"
CDS_LIB"mstr_standard";
"B \NAC \NWC"9;
"S \NAC"
BN"20"50;
%"TAP"
"6","(-5575,2575)","0","mstr_standard","I43";
;
HDL_TAP"TRUE"
BODY_TYPE"PLUMBING"
CDS_LIB"mstr_standard";
"B \NAC \NWC"9;
"S \NAC"
BN"21"51;
%"TAP"
"6","(-5575,2625)","0","mstr_standard","I44";
;
HDL_TAP"TRUE"
BODY_TYPE"PLUMBING"
CDS_LIB"mstr_standard";
"B \NAC \NWC"9;
"S \NAC"
BN"22"52;
%"TAP"
"6","(-5575,2675)","0","mstr_standard","I45";
;
HDL_TAP"TRUE"
BODY_TYPE"PLUMBING"
CDS_LIB"mstr_standard";
"B \NAC \NWC"9;
"S \NAC"
BN"23"53;
%"TAP"
"6","(-5575,2725)","0","mstr_standard","I46";
;
HDL_TAP"TRUE"
BODY_TYPE"PLUMBING"
CDS_LIB"mstr_standard";
"B \NAC \NWC"9;
"S \NAC"
BN"24"54;
%"TAP"
"6","(-5575,2825)","0","mstr_standard","I47";
;
HDL_TAP"TRUE"
BODY_TYPE"PLUMBING"
CDS_LIB"mstr_standard";
"B \NAC \NWC"9;
"S \NAC"
BN"26"56;
%"TAP"
"6","(-5575,2775)","0","mstr_standard","I48";
;
HDL_TAP"TRUE"
BODY_TYPE"PLUMBING"
CDS_LIB"mstr_standard";
"B \NAC \NWC"9;
"S \NAC"
BN"25"55;
%"TAP"
"6","(-5575,2875)","0","mstr_standard","I49";
;
HDL_TAP"TRUE"
BODY_TYPE"PLUMBING"
CDS_LIB"mstr_standard";
"B \NAC \NWC"9;
"S \NAC"
BN"27"57;
%"TAP"
"6","(-5575,625)","0","mstr_standard","I5";
;
HDL_TAP"TRUE"
BODY_TYPE"PLUMBING"
CDS_LIB"mstr_standard";
"B \NAC \NWC"10;
"S \NAC"
BN"0"37;
%"TAP"
"6","(-5575,2925)","0","mstr_standard","I50";
;
HDL_TAP"TRUE"
BODY_TYPE"PLUMBING"
CDS_LIB"mstr_standard";
"B \NAC \NWC"9;
"S \NAC"
BN"28"58;
%"TAP"
"6","(-5575,2975)","0","mstr_standard","I51";
;
HDL_TAP"TRUE"
BODY_TYPE"PLUMBING"
CDS_LIB"mstr_standard";
"B \NAC \NWC"9;
"S \NAC"
BN"29"59;
%"TAP"
"6","(-5575,3075)","0","mstr_standard","I52";
;
HDL_TAP"TRUE"
BODY_TYPE"PLUMBING"
CDS_LIB"mstr_standard";
"B \NAC \NWC"9;
"S \NAC"
BN"31"61;
%"TAP"
"6","(-5575,3025)","0","mstr_standard","I53";
;
HDL_TAP"TRUE"
BODY_TYPE"PLUMBING"
CDS_LIB"mstr_standard";
"B \NAC \NWC"9;
"S \NAC"
BN"30"60;
%"TAP"
"6","(-5575,3125)","0","mstr_standard","I54";
;
HDL_TAP"TRUE"
BODY_TYPE"PLUMBING"
CDS_LIB"mstr_standard";
"B \NAC \NWC"9;
"S \NAC"
BN"32"62;
%"TAP"
"6","(-5575,3175)","0","mstr_standard","I55";
;
HDL_TAP"TRUE"
BODY_TYPE"PLUMBING"
CDS_LIB"mstr_standard";
"B \NAC \NWC"9;
"S \NAC"
BN"33"63;
%"TAP"
"6","(-5575,3225)","0","mstr_standard","I56";
;
HDL_TAP"TRUE"
BODY_TYPE"PLUMBING"
CDS_LIB"mstr_standard";
"B \NAC \NWC"9;
"S \NAC"
BN"34"64;
%"TAP"
"6","(-5575,3325)","0","mstr_standard","I57";
;
HDL_TAP"TRUE"
BODY_TYPE"PLUMBING"
CDS_LIB"mstr_standard";
"B \NAC \NWC"9;
"S \NAC"
BN"36"66;
%"TAP"
"6","(-5575,3275)","0","mstr_standard","I58";
;
HDL_TAP"TRUE"
BODY_TYPE"PLUMBING"
CDS_LIB"mstr_standard";
"B \NAC \NWC"9;
"S \NAC"
BN"35"65;
%"TAP"
"6","(-5575,3375)","0","mstr_standard","I59";
;
HDL_TAP"TRUE"
BODY_TYPE"PLUMBING"
CDS_LIB"mstr_standard";
"B \NAC \NWC"9;
"S \NAC"
BN"37"67;
%"TAP"
"6","(-5575,675)","0","mstr_standard","I6";
;
HDL_TAP"TRUE"
BODY_TYPE"PLUMBING"
CDS_LIB"mstr_standard";
"B \NAC \NWC"10;
"S \NAC"
BN"1"38;
%"TAP"
"6","(-5575,3425)","0","mstr_standard","I60";
;
HDL_TAP"TRUE"
BODY_TYPE"PLUMBING"
CDS_LIB"mstr_standard";
"B \NAC \NWC"9;
"S \NAC"
BN"38"68;
%"TAP"
"6","(-5575,3475)","0","mstr_standard","I61";
;
HDL_TAP"TRUE"
BODY_TYPE"PLUMBING"
CDS_LIB"mstr_standard";
"B \NAC \NWC"9;
"S \NAC"
BN"39"69;
%"TAP"
"6","(-5575,3525)","0","mstr_standard","I62";
;
HDL_TAP"TRUE"
BODY_TYPE"PLUMBING"
CDS_LIB"mstr_standard";
"B \NAC \NWC"9;
"S \NAC"
BN"40"70;
%"TAP"
"6","(-5575,3575)","0","mstr_standard","I63";
;
HDL_TAP"TRUE"
BODY_TYPE"PLUMBING"
CDS_LIB"mstr_standard";
"B \NAC \NWC"9;
"S \NAC"
BN"41"71;
%"TAP"
"6","(-5575,3625)","0","mstr_standard","I64";
;
HDL_TAP"TRUE"
BODY_TYPE"PLUMBING"
CDS_LIB"mstr_standard";
"B \NAC \NWC"9;
"S \NAC"
BN"42"72;
%"TAP"
"6","(-5575,3675)","0","mstr_standard","I65";
;
HDL_TAP"TRUE"
BODY_TYPE"PLUMBING"
CDS_LIB"mstr_standard";
"B \NAC \NWC"9;
"S \NAC"
BN"43"73;
%"TAP"
"6","(-5575,3725)","0","mstr_standard","I66";
;
HDL_TAP"TRUE"
BODY_TYPE"PLUMBING"
CDS_LIB"mstr_standard";
"B \NAC \NWC"9;
"S \NAC"
BN"44"74;
%"TAP"
"6","(-5575,3775)","0","mstr_standard","I67";
;
HDL_TAP"TRUE"
BODY_TYPE"PLUMBING"
CDS_LIB"mstr_standard";
"B \NAC \NWC"9;
"S \NAC"
BN"45"75;
%"TAP"
"6","(-5575,3825)","0","mstr_standard","I68";
;
HDL_TAP"TRUE"
BODY_TYPE"PLUMBING"
CDS_LIB"mstr_standard";
"B \NAC \NWC"9;
"S \NAC"
BN"46"76;
%"TAP"
"6","(-5575,3875)","0","mstr_standard","I69";
;
HDL_TAP"TRUE"
BODY_TYPE"PLUMBING"
CDS_LIB"mstr_standard";
"B \NAC \NWC"9;
"S \NAC"
BN"47"77;
%"TAP"
"6","(-5575,775)","0","mstr_standard","I7";
;
HDL_TAP"TRUE"
BODY_TYPE"PLUMBING"
CDS_LIB"mstr_standard";
"B \NAC \NWC"10;
"S \NAC"
BN"3"40;
%"TAP"
"6","(-5575,3925)","0","mstr_standard","I70";
;
HDL_TAP"TRUE"
BODY_TYPE"PLUMBING"
CDS_LIB"mstr_standard";
"B \NAC \NWC"9;
"S \NAC"
BN"48"78;
%"TAP"
"6","(-5575,3975)","0","mstr_standard","I71";
;
HDL_TAP"TRUE"
BODY_TYPE"PLUMBING"
CDS_LIB"mstr_standard";
"B \NAC \NWC"9;
"S \NAC"
BN"49"79;
%"TAP"
"6","(-5575,4025)","0","mstr_standard","I73";
;
HDL_TAP"TRUE"
BODY_TYPE"PLUMBING"
CDS_LIB"mstr_standard";
"B \NAC \NWC"9;
"S \NAC"
BN"50"80;
%"TAP"
"6","(-5575,4075)","0","mstr_standard","I74";
;
HDL_TAP"TRUE"
BODY_TYPE"PLUMBING"
CDS_LIB"mstr_standard";
"B \NAC \NWC"9;
"S \NAC"
BN"51"81;
%"TAP"
"6","(-5575,4125)","0","mstr_standard","I75";
;
HDL_TAP"TRUE"
BODY_TYPE"PLUMBING"
CDS_LIB"mstr_standard";
"B \NAC \NWC"9;
"S \NAC"
BN"52"82;
%"TAP"
"6","(-5575,4175)","0","mstr_standard","I76";
;
HDL_TAP"TRUE"
BODY_TYPE"PLUMBING"
CDS_LIB"mstr_standard";
"B \NAC \NWC"9;
"S \NAC"
BN"53"83;
%"TAP"
"6","(-5575,4225)","0","mstr_standard","I77";
;
HDL_TAP"TRUE"
BODY_TYPE"PLUMBING"
CDS_LIB"mstr_standard";
"B \NAC \NWC"9;
"S \NAC"
BN"54"84;
%"TAP"
"6","(-5575,4275)","0","mstr_standard","I78";
;
HDL_TAP"TRUE"
BODY_TYPE"PLUMBING"
CDS_LIB"mstr_standard";
"B \NAC \NWC"9;
"S \NAC"
BN"55"85;
%"TAP"
"6","(-5575,4325)","0","mstr_standard","I79";
;
HDL_TAP"TRUE"
BODY_TYPE"PLUMBING"
CDS_LIB"mstr_standard";
"B \NAC \NWC"9;
"S \NAC"
BN"56"86;
%"TAP"
"6","(-5575,725)","0","mstr_standard","I8";
;
HDL_TAP"TRUE"
BODY_TYPE"PLUMBING"
CDS_LIB"mstr_standard";
"B \NAC \NWC"10;
"S \NAC"
BN"2"39;
%"TAP"
"6","(-5575,4375)","0","mstr_standard","I80";
;
HDL_TAP"TRUE"
BODY_TYPE"PLUMBING"
CDS_LIB"mstr_standard";
"B \NAC \NWC"9;
"S \NAC"
BN"57"87;
%"TAP"
"6","(-5575,4425)","0","mstr_standard","I81";
;
HDL_TAP"TRUE"
BODY_TYPE"PLUMBING"
CDS_LIB"mstr_standard";
"B \NAC \NWC"9;
"S \NAC"
BN"58"88;
%"TAP"
"6","(-5575,4475)","0","mstr_standard","I82";
;
HDL_TAP"TRUE"
BODY_TYPE"PLUMBING"
CDS_LIB"mstr_standard";
"B \NAC \NWC"9;
"S \NAC"
BN"59"89;
%"TAP"
"6","(-5575,4525)","0","mstr_standard","I83";
;
HDL_TAP"TRUE"
BODY_TYPE"PLUMBING"
CDS_LIB"mstr_standard";
"B \NAC \NWC"9;
"S \NAC"
BN"60"90;
%"TAP"
"6","(-5575,4575)","0","mstr_standard","I84";
;
HDL_TAP"TRUE"
BODY_TYPE"PLUMBING"
CDS_LIB"mstr_standard";
"B \NAC \NWC"9;
"S \NAC"
BN"61"91;
%"TAP"
"6","(-5575,4625)","0","mstr_standard","I85";
;
HDL_TAP"TRUE"
BODY_TYPE"PLUMBING"
CDS_LIB"mstr_standard";
"B \NAC \NWC"9;
"S \NAC"
BN"62"92;
%"TAP"
"6","(-5575,4675)","0","mstr_standard","I86";
;
HDL_TAP"TRUE"
BODY_TYPE"PLUMBING"
CDS_LIB"mstr_standard";
"B \NAC \NWC"9;
"S \NAC"
BN"63"93;
%"TAP"
"6","(-2850,775)","2","mstr_standard","I87";
;
HDL_TAP"TRUE"
BODY_TYPE"PLUMBING"
CDS_LIB"mstr_standard";
"B \NAC \NWC"4;
"S \NAC"
BN"1"116;
%"TAP"
"6","(-2850,725)","2","mstr_standard","I88";
;
HDL_TAP"TRUE"
BODY_TYPE"PLUMBING"
CDS_LIB"mstr_standard";
"B \NAC \NWC"4;
"S \NAC"
BN"0"115;
%"TAP"
"6","(-2850,825)","2","mstr_standard","I89";
;
HDL_TAP"TRUE"
BODY_TYPE"PLUMBING"
CDS_LIB"mstr_standard";
"B \NAC \NWC"5;
"S \NAC"
BN"0"113;
%"TAP"
"6","(-5575,875)","0","mstr_standard","I9";
;
HDL_TAP"TRUE"
BODY_TYPE"PLUMBING"
CDS_LIB"mstr_standard";
"B \NAC \NWC"11;
"S \NAC"
BN"1"34;
%"TAP"
"6","(-2850,875)","2","mstr_standard","I90";
;
HDL_TAP"TRUE"
BODY_TYPE"PLUMBING"
CDS_LIB"mstr_standard";
"B \NAC \NWC"5;
"S \NAC"
BN"1"114;
%"TAP"
"6","(-2850,1075)","2","mstr_standard","I91";
;
HDL_TAP"TRUE"
BODY_TYPE"PLUMBING"
CDS_LIB"mstr_standard";
"B \NAC \NWC"7;
"S \NAC"
BN"2"103;
%"TAP"
"6","(-2850,1025)","2","mstr_standard","I92";
;
HDL_TAP"TRUE"
BODY_TYPE"PLUMBING"
CDS_LIB"mstr_standard";
"B \NAC \NWC"7;
"S \NAC"
BN"1"102;
%"TAP"
"6","(-2850,975)","2","mstr_standard","I93";
;
HDL_TAP"TRUE"
BODY_TYPE"PLUMBING"
CDS_LIB"mstr_standard";
"B \NAC \NWC"7;
"S \NAC"
BN"0"101;
%"TAP"
"6","(-2850,1175)","2","mstr_standard","I94";
;
HDL_TAP"TRUE"
BODY_TYPE"PLUMBING"
CDS_LIB"mstr_standard";
"B \NAC \NWC"7;
"S \NAC"
BN"4"105;
%"TAP"
"6","(-2850,1125)","2","mstr_standard","I95";
;
HDL_TAP"TRUE"
BODY_TYPE"PLUMBING"
CDS_LIB"mstr_standard";
"B \NAC \NWC"7;
"S \NAC"
BN"3"104;
%"TAP"
"6","(-2850,1225)","2","mstr_standard","I96";
;
HDL_TAP"TRUE"
BODY_TYPE"PLUMBING"
CDS_LIB"mstr_standard";
"B \NAC \NWC"7;
"S \NAC"
BN"5"106;
%"TAP"
"6","(-2850,1275)","2","mstr_standard","I97";
;
HDL_TAP"TRUE"
BODY_TYPE"PLUMBING"
CDS_LIB"mstr_standard";
"B \NAC \NWC"7;
"S \NAC"
BN"6"107;
%"TAP"
"6","(-2850,1325)","2","mstr_standard","I98";
;
HDL_TAP"TRUE"
BODY_TYPE"PLUMBING"
CDS_LIB"mstr_standard";
"B \NAC \NWC"7;
"S \NAC"
BN"7"108;
%"TAP"
"6","(-2850,1425)","2","mstr_standard","I99";
;
HDL_TAP"TRUE"
BODY_TYPE"PLUMBING"
CDS_LIB"mstr_standard";
"B \NAC \NWC"8;
"S \NAC"
BN"0"94;
END.
